# T6G (Grand Teton) — schematic netlist excerpt (pin names and nets, part order shuffled) for the footprints in the layout excerpt that follows; sources: Cadence DE-HDL packaged netlist, KiCad conversion of 04192023_DAF0TMB3IC0_F0TG_MB_C_brd_V02_OCP.brd

C492  Q_CAP  1UF 4V 20% X6S  pkg 0201  page 356 : A = P0V9_CPU1_RT3_2A ; B = GND
L6003  Q_INDUCTOR  BLM21PG221SN1D IND  pkg SMLF  page 179 : \1\ = P3V3_AUX ; \2\ = P3V3_AUX_CPU0_USB2_AVDD33
R618  Q_RES  0 5% CHIP  pkg 0402LF  page 54 : A = CPU1_XTRIG_R2_L5 ; B = CPU1_XTRIG_L5
C415  Q_CAP  1UF 4V 20% X6S  pkg 0201  page 345 : A = P0V9_CPU1_RT2_2A ; B = GND

(kicad_pcb
	(version 20260206)
	(generator "pcbnew")
	(generator_version "10.0")
	(general
		(thickness 1.6)
		(legacy_teardrops no)
	)
	(paper "A4")
	(title_block
		(title "04192023_DAF0TMB3IC0_F0TG_MB_C_brd_V02_OCP.brd")
		(comment 1 "Grand Teton / footprints 7618-7621 of 8354")
	)
	(layers
		(0 "F.Cu" signal "TOP")
		(4 "In1.Cu" signal "GND")
		(6 "In2.Cu" signal "IN1")
		(8 "In3.Cu" signal "GND1")
		(10 "In4.Cu" signal "IN2")
		(12 "In5.Cu" signal "GND2")
		(14 "In6.Cu" signal "IN3")
		(16 "In7.Cu" signal "GND3")
		(18 "In8.Cu" signal "VCC")
		(20 "In9.Cu" signal "VCC1")
		(22 "In10.Cu" signal "GND4")
		(24 "In11.Cu" signal "IN4")
		(26 "In12.Cu" signal "GND5")
		(28 "In13.Cu" signal "IN5")
		(30 "In14.Cu" signal "GND6")
		(32 "In15.Cu" signal "IN6")
		(34 "In16.Cu" signal "GND7")
		(2 "B.Cu" signal "BOTTOM")
		(9 "F.Adhes" user "F.Adhesive")
		(11 "B.Adhes" user "B.Adhesive")
		(13 "F.Paste" user "Package Geometry/Pastemask Top")
		(15 "B.Paste" user "Package Geometry/Pastemask Bottom")
		(5 "F.SilkS" user "Ref Des/Silkscreen Top")
		(7 "B.SilkS" user "Ref Des/Silkscreen Bottom")
		(1 "F.Mask" user "Board Geometry/Soldermask Top")
		(3 "B.Mask" user "Board Geometry/Soldermask Bottom")
		(17 "Dwgs.User" user "User.Drawings")
		(19 "Cmts.User" user "User.Comments")
		(21 "Eco1.User" user "User.Eco1")
		(23 "Eco2.User" user "User.Eco2")
		(25 "Edge.Cuts" user "Board Geometry/Outline")
		(27 "Margin" user)
		(31 "F.CrtYd" user "Package Geometry/Place Bound Top")
		(29 "B.CrtYd" user "Package Geometry/Place Bound Bottom")
		(35 "F.Fab" user "Ref Des/Assembly Top")
		(33 "B.Fab" user "Ref Des/Assembly Bottom")
	)
	(footprint ""
		(layer "B.Cu")
		(at 91.392502 -207.41005 90)
		(property "Reference" "R618"
			(at 0 0 90)
			(layer "B.SilkS")
			(hide yes)
			(effects
				(font
					(size 1.27 1.27)
				)
				(justify mirror)
			)
		)
		(property "Value" ""
			(at 0 0 90)
			(layer "B.Fab")
			(effects
				(font
					(size 1.27 1.27)
				)
				(justify mirror)
			)
		)
		(duplicate_pad_numbers_are_jumpers no)
		(fp_line
			(start 0.7874 -0.4064)
			(end -0.7874 -0.4064)
			(stroke
				(width 0.1524)
				(type default)
			)
			(layer "B.SilkS")
		)
		(fp_line
			(start -0.7874 -0.4064)
			(end -0.7874 0.4064)
			(stroke
				(width 0.1524)
				(type default)
			)
			(layer "B.SilkS")
		)
		(fp_line
			(start 0.7874 0.4064)
			(end 0.7874 -0.4064)
			(stroke
				(width 0.1524)
				(type default)
			)
			(layer "B.SilkS")
		)
		(fp_line
			(start -0.7874 0.4064)
			(end 0.7874 0.4064)
			(stroke
				(width 0.1524)
				(type default)
			)
			(layer "B.SilkS")
		)
		(fp_line
			(start 0.67945 -0.305054)
			(end 0.12065 -0.305054)
			(stroke
				(width 0.1)
				(type default)
			)
			(layer "B.Fab")
		)
		(fp_line
			(start 0.12065 -0.305054)
			(end 0.12065 -0.2794)
			(stroke
				(width 0.1)
				(type default)
			)
			(layer "B.Fab")
		)
		(fp_line
			(start -0.12065 -0.3048)
			(end -0.67945 -0.3048)
			(stroke
				(width 0.1)
				(type default)
			)
			(layer "B.Fab")
		)
		(fp_line
			(start -0.67945 -0.3048)
			(end -0.67945 0.3048)
			(stroke
				(width 0.1)
				(type default)
			)
			(layer "B.Fab")
		)
		(fp_line
			(start 0.12065 -0.2794)
			(end -0.12065 -0.2794)
			(stroke
				(width 0.1)
				(type default)
			)
			(layer "B.Fab")
		)
		(fp_line
			(start -0.12065 -0.2794)
			(end -0.12065 -0.3048)
			(stroke
				(width 0.1)
				(type default)
			)
			(layer "B.Fab")
		)
		(fp_line
			(start 0.12065 0.2794)
			(end 0.12065 0.3048)
			(stroke
				(width 0.1)
				(type default)
			)
			(layer "B.Fab")
		)
		(fp_line
			(start -0.120396 0.2794)
			(end 0.12065 0.2794)
			(stroke
				(width 0.1)
				(type default)
			)
			(layer "B.Fab")
		)
		(fp_line
			(start 0.67945 0.3048)
			(end 0.67945 -0.305054)
			(stroke
				(width 0.1)
				(type default)
			)
			(layer "B.Fab")
		)
		(fp_line
			(start 0.12065 0.3048)
			(end 0.67945 0.3048)
			(stroke
				(width 0.1)
				(type default)
			)
			(layer "B.Fab")
		)
		(fp_line
			(start -0.120396 0.3048)
			(end -0.120396 0.2794)
			(stroke
				(width 0.1)
				(type default)
			)
			(layer "B.Fab")
		)
		(fp_line
			(start -0.67945 0.3048)
			(end -0.120396 0.3048)
			(stroke
				(width 0.1)
				(type default)
			)
			(layer "B.Fab")
		)
		(pad "1" smd circle
			(at 0.40005 0 270)
			(size 0 0)
			(layers "B.Cu" "B.Mask" "B.Paste")
			(net "CPU1_XTRIG_R2_L5")
		)
		(pad "2" smd circle
			(at -0.40005 0 270)
			(size 0 0)
			(layers "B.Cu" "B.Mask" "B.Paste")
			(net "CPU1_XTRIG_L5")
		)
	)
	(footprint ""
		(layer "B.Cu")
		(at 149.406356 -386.766562 90)
		(property "Reference" "C415"
			(at 0 0 90)
			(layer "B.SilkS")
			(hide yes)
			(effects
				(font
					(size 1.27 1.27)
				)
				(justify mirror)
			)
		)
		(property "Value" ""
			(at 0 0 90)
			(layer "B.Fab")
			(effects
				(font
					(size 1.27 1.27)
				)
				(justify mirror)
			)
		)
		(duplicate_pad_numbers_are_jumpers no)
		(fp_line
			(start 0.299974 -0.150114)
			(end -0.299974 -0.150114)
			(stroke
				(width 0.1)
				(type default)
			)
			(layer "B.Fab")
		)
		(fp_line
			(start -0.299974 -0.150114)
			(end -0.299974 0.150114)
			(stroke
				(width 0.1)
				(type default)
			)
			(layer "B.Fab")
		)
		(fp_line
			(start 0.299974 0.150114)
			(end 0.299974 -0.150114)
			(stroke
				(width 0.1)
				(type default)
			)
			(layer "B.Fab")
		)
		(fp_line
			(start -0.299974 0.150114)
			(end 0.299974 0.150114)
			(stroke
				(width 0.1)
				(type default)
			)
			(layer "B.Fab")
		)
		(pad "1" smd rect
			(at 0.2667 0 270)
			(size 0.3048 0.381)
			(layers "B.Cu" "B.Mask" "B.Paste")
			(net "P0V9_CPU1_RT2_2A")
		)
		(pad "2" smd rect
			(at -0.2667 0 270)
			(size 0.3048 0.381)
			(layers "B.Cu" "B.Mask" "B.Paste")
			(net "GND")
		)
	)
	(footprint ""
		(layer "B.Cu")
		(at 130.07848 -386.766562 90)
		(property "Reference" "C492"
			(at 0 0 90)
			(layer "B.SilkS")
			(hide yes)
			(effects
				(font
					(size 1.27 1.27)
				)
				(justify mirror)
			)
		)
		(property "Value" ""
			(at 0 0 90)
			(layer "B.Fab")
			(effects
				(font
					(size 1.27 1.27)
				)
				(justify mirror)
			)
		)
		(duplicate_pad_numbers_are_jumpers no)
		(fp_line
			(start 0.299974 -0.150114)
			(end -0.299974 -0.150114)
			(stroke
				(width 0.1)
				(type default)
			)
			(layer "B.Fab")
		)
		(fp_line
			(start -0.299974 -0.150114)
			(end -0.299974 0.150114)
			(stroke
				(width 0.1)
				(type default)
			)
			(layer "B.Fab")
		)
		(fp_line
			(start 0.299974 0.150114)
			(end 0.299974 -0.150114)
			(stroke
				(width 0.1)
				(type default)
			)
			(layer "B.Fab")
		)
		(fp_line
			(start -0.299974 0.150114)
			(end 0.299974 0.150114)
			(stroke
				(width 0.1)
				(type default)
			)
			(layer "B.Fab")
		)
		(pad "1" smd rect
			(at 0.2667 0 270)
			(size 0.3048 0.381)
			(layers "B.Cu" "B.Mask" "B.Paste")
			(net "P0V9_CPU1_RT3_2A")
		)
		(pad "2" smd rect
			(at -0.2667 0 270)
			(size 0.3048 0.381)
			(layers "B.Cu" "B.Mask" "B.Paste")
			(net "GND")
		)
	)
	(footprint ""
		(layer "B.Cu")
		(at 105.454196 -27.800808 -90)
		(property "Reference" "L6003"
			(at 0 0 90)
			(layer "B.SilkS")
			(hide yes)
			(effects
				(font
					(size 1.27 1.27)
				)
				(justify mirror)
			)
		)
		(property "Value" ""
			(at 0 0 90)
			(layer "B.Fab")
			(effects
				(font
					(size 1.27 1.27)
				)
				(justify mirror)
			)
		)
		(duplicate_pad_numbers_are_jumpers no)
		(fp_line
			(start -1.63576 0.8128)
			(end 1.63576 0.8128)
			(stroke
				(width 0.1524)
				(type default)
			)
			(layer "B.SilkS")
		)
		(fp_line
			(start -1.63576 -0.8128)
			(end -1.63576 0.8128)
			(stroke
				(width 0.1524)
				(type default)
			)
			(layer "B.SilkS")
		)
		(fp_line
			(start 1.63576 -0.8128)
			(end 1.63576 0.8128)
			(stroke
				(width 0.1524)
				(type default)
			)
			(layer "B.SilkS")
		)
		(fp_line
			(start 1.63576 -0.8128)
			(end -1.63576 -0.8128)
			(stroke
				(width 0.1524)
				(type default)
			)
			(layer "B.SilkS")
		)
		(fp_line
			(start -1.560576 0.7366)
			(end -1.560576 -0.738632)
			(stroke
				(width 0.1)
				(type default)
			)
			(layer "B.Fab")
		)
		(fp_line
			(start -1.524 0.7366)
			(end -1.560576 0.7366)
			(stroke
				(width 0.1)
				(type default)
			)
			(layer "B.Fab")
		)
		(fp_line
			(start 1.524 0.7366)
			(end -1.524 0.7366)
			(stroke
				(width 0.1)
				(type default)
			)
			(layer "B.Fab")
		)
		(fp_line
			(start 1.56083 0.7366)
			(end 1.524 0.7366)
			(stroke
				(width 0.1)
				(type default)
			)
			(layer "B.Fab")
		)
		(fp_line
			(start -1.560576 -0.738632)
			(end 1.56083 -0.738632)
			(stroke
				(width 0.1)
				(type default)
			)
			(layer "B.Fab")
		)
		(fp_line
			(start 1.56083 -0.738632)
			(end 1.56083 0.7366)
			(stroke
				(width 0.1)
				(type default)
			)
			(layer "B.Fab")
		)
		(pad "1" smd rect
			(at 0.94996 0 270)
			(size 1.1176 1.3716)
			(layers "B.Cu" "B.Mask" "B.Paste")
			(net "P3V3_AUX")
		)
		(pad "2" smd rect
			(at -0.94996 0 270)
			(size 1.1176 1.3716)
			(layers "B.Cu" "B.Mask" "B.Paste")
			(net "P3V3_AUX_CPU0_USB2_AVDD33")
		)
	)
)
